# S9S_MB_2U (Grand Teton) — schematic netlist excerpt (pin names and nets, part order shuffled) for the footprints in the layout excerpt that follows; sources: Cadence DE-HDL packaged netlist, KiCad conversion of 03242023_DA0F0TMBIJ0_F0T_Motherboard_J_brd_V01_OCP.brd

R25  Q_RES  10 1% CHIP  pkg 0402LF  page 16 : A = DBP_CPU0_HOOK9_MBP3_GTL_QS_R_N ; B = DBP_CPU_HOOK9_MBP3_GTL_QS_N
C458  Q_CAP  47UF 4V 20% X6S  pkg C0805  page 79 : A = PVCCFA_EHV_FIVRA_CPU1 ; B = GND
PC1750  Q_CAP  33NF 25V 10% EMPTY  pkg C0402  page 304 : A = P12V_AUX ; B = P12V_HSC_GATE2

(kicad_pcb
	(version 20260206)
	(generator "pcbnew")
	(generator_version "10.0")
	(general
		(thickness 1.6)
		(legacy_teardrops no)
	)
	(paper "A4")
	(title_block
		(title "03242023_DA0F0TMBIJ0_F0T_Motherboard_J_brd_V01_OCP.brd")
		(comment 1 "Grand Teton / footprints 4765-4767 of 6105")
	)
	(layers
		(0 "F.Cu" signal "TOP")
		(4 "In1.Cu" signal "GND")
		(6 "In2.Cu" signal "IN1")
		(8 "In3.Cu" signal "GND1")
		(10 "In4.Cu" signal "IN2")
		(12 "In5.Cu" signal "GND2")
		(14 "In6.Cu" signal "IN3")
		(16 "In7.Cu" signal "GND3")
		(18 "In8.Cu" signal "VCC")
		(20 "In9.Cu" signal "VCC1")
		(22 "In10.Cu" signal "GND4")
		(24 "In11.Cu" signal "IN4")
		(26 "In12.Cu" signal "GND5")
		(28 "In13.Cu" signal "IN5")
		(30 "In14.Cu" signal "GND6")
		(32 "In15.Cu" signal "IN6")
		(34 "In16.Cu" signal "GND7")
		(2 "B.Cu" signal "BOTTOM")
		(9 "F.Adhes" user "F.Adhesive")
		(11 "B.Adhes" user "B.Adhesive")
		(13 "F.Paste" user "Package Geometry/Pastemask Top")
		(15 "B.Paste" user "Package Geometry/Pastemask Bottom")
		(5 "F.SilkS" user "Ref Des/Silkscreen Top")
		(7 "B.SilkS" user "Ref Des/Silkscreen Bottom")
		(1 "F.Mask" user "Board Geometry/Soldermask Top")
		(3 "B.Mask" user "Board Geometry/Soldermask Bottom")
		(17 "Dwgs.User" user "User.Drawings")
		(19 "Cmts.User" user "User.Comments")
		(21 "Eco1.User" user "User.Eco1")
		(23 "Eco2.User" user "User.Eco2")
		(25 "Edge.Cuts" user "Board Geometry/Outline")
		(27 "Margin" user)
		(31 "F.CrtYd" user "Package Geometry/Place Bound Top")
		(29 "B.CrtYd" user "Package Geometry/Place Bound Bottom")
		(35 "F.Fab" user "Ref Des/Assembly Top")
		(33 "B.Fab" user "Ref Des/Assembly Bottom")
	)
	(footprint ""
		(layer "B.Cu")
		(at 243.485924 -396.056104 180)
		(property "Reference" "PC1750"
			(at 0 0 0)
			(layer "B.SilkS")
			(hide yes)
			(effects
				(font
					(size 1.27 1.27)
				)
				(justify mirror)
			)
		)
		(property "Value" ""
			(at 0 0 0)
			(layer "B.Fab")
			(effects
				(font
					(size 1.27 1.27)
				)
				(justify mirror)
			)
		)
		(duplicate_pad_numbers_are_jumpers no)
		(fp_line
			(start 0.7874 0.4064)
			(end 0.7874 -0.4064)
			(stroke
				(width 0.1524)
				(type default)
			)
			(layer "B.SilkS")
		)
		(fp_line
			(start 0.7874 -0.4064)
			(end -0.7874 -0.4064)
			(stroke
				(width 0.1524)
				(type default)
			)
			(layer "B.SilkS")
		)
		(fp_line
			(start -0.7874 0.4064)
			(end 0.7874 0.4064)
			(stroke
				(width 0.1524)
				(type default)
			)
			(layer "B.SilkS")
		)
		(fp_line
			(start -0.7874 -0.4064)
			(end -0.7874 0.4064)
			(stroke
				(width 0.1524)
				(type default)
			)
			(layer "B.SilkS")
		)
		(fp_line
			(start 0.67945 0.3048)
			(end 0.67945 -0.305054)
			(stroke
				(width 0.1)
				(type default)
			)
			(layer "B.Fab")
		)
		(fp_line
			(start 0.67945 -0.305054)
			(end 0.12065 -0.305054)
			(stroke
				(width 0.1)
				(type default)
			)
			(layer "B.Fab")
		)
		(fp_line
			(start 0.12065 0.3048)
			(end 0.67945 0.3048)
			(stroke
				(width 0.1)
				(type default)
			)
			(layer "B.Fab")
		)
		(fp_line
			(start 0.12065 0.2794)
			(end 0.12065 0.3048)
			(stroke
				(width 0.1)
				(type default)
			)
			(layer "B.Fab")
		)
		(fp_line
			(start 0.12065 -0.2794)
			(end -0.12065 -0.2794)
			(stroke
				(width 0.1)
				(type default)
			)
			(layer "B.Fab")
		)
		(fp_line
			(start 0.12065 -0.305054)
			(end 0.12065 -0.2794)
			(stroke
				(width 0.1)
				(type default)
			)
			(layer "B.Fab")
		)
		(fp_line
			(start -0.120396 0.3048)
			(end -0.120396 0.2794)
			(stroke
				(width 0.1)
				(type default)
			)
			(layer "B.Fab")
		)
		(fp_line
			(start -0.120396 0.2794)
			(end 0.12065 0.2794)
			(stroke
				(width 0.1)
				(type default)
			)
			(layer "B.Fab")
		)
		(fp_line
			(start -0.12065 -0.2794)
			(end -0.12065 -0.3048)
			(stroke
				(width 0.1)
				(type default)
			)
			(layer "B.Fab")
		)
		(fp_line
			(start -0.12065 -0.3048)
			(end -0.67945 -0.3048)
			(stroke
				(width 0.1)
				(type default)
			)
			(layer "B.Fab")
		)
		(fp_line
			(start -0.67945 0.3048)
			(end -0.120396 0.3048)
			(stroke
				(width 0.1)
				(type default)
			)
			(layer "B.Fab")
		)
		(fp_line
			(start -0.67945 -0.3048)
			(end -0.67945 0.3048)
			(stroke
				(width 0.1)
				(type default)
			)
			(layer "B.Fab")
		)
		(pad "1" smd circle
			(at 0.40005 0)
			(size 0 0)
			(layers "B.Cu" "B.Mask" "B.Paste")
			(net "P12V_AUX")
		)
		(pad "2" smd circle
			(at -0.40005 0)
			(size 0 0)
			(layers "B.Cu" "B.Mask" "B.Paste")
			(net "P12V_HSC_GATE2")
		)
	)
	(footprint ""
		(layer "B.Cu")
		(at 332.447138 -190.82893 90)
		(property "Reference" "R25"
			(at 0 0 90)
			(layer "B.SilkS")
			(hide yes)
			(effects
				(font
					(size 1.27 1.27)
				)
				(justify mirror)
			)
		)
		(property "Value" ""
			(at 0 0 90)
			(layer "B.Fab")
			(effects
				(font
					(size 1.27 1.27)
				)
				(justify mirror)
			)
		)
		(duplicate_pad_numbers_are_jumpers no)
		(fp_line
			(start 0.7874 -0.4064)
			(end -0.7874 -0.4064)
			(stroke
				(width 0.1524)
				(type default)
			)
			(layer "B.SilkS")
		)
		(fp_line
			(start -0.7874 -0.4064)
			(end -0.7874 0.4064)
			(stroke
				(width 0.1524)
				(type default)
			)
			(layer "B.SilkS")
		)
		(fp_line
			(start 0.7874 0.4064)
			(end 0.7874 -0.4064)
			(stroke
				(width 0.1524)
				(type default)
			)
			(layer "B.SilkS")
		)
		(fp_line
			(start -0.7874 0.4064)
			(end 0.7874 0.4064)
			(stroke
				(width 0.1524)
				(type default)
			)
			(layer "B.SilkS")
		)
		(fp_line
			(start 0.67945 -0.305054)
			(end 0.12065 -0.305054)
			(stroke
				(width 0.1)
				(type default)
			)
			(layer "B.Fab")
		)
		(fp_line
			(start 0.12065 -0.305054)
			(end 0.12065 -0.2794)
			(stroke
				(width 0.1)
				(type default)
			)
			(layer "B.Fab")
		)
		(fp_line
			(start -0.12065 -0.3048)
			(end -0.67945 -0.3048)
			(stroke
				(width 0.1)
				(type default)
			)
			(layer "B.Fab")
		)
		(fp_line
			(start -0.67945 -0.3048)
			(end -0.67945 0.3048)
			(stroke
				(width 0.1)
				(type default)
			)
			(layer "B.Fab")
		)
		(fp_line
			(start 0.12065 -0.2794)
			(end -0.12065 -0.2794)
			(stroke
				(width 0.1)
				(type default)
			)
			(layer "B.Fab")
		)
		(fp_line
			(start -0.12065 -0.2794)
			(end -0.12065 -0.3048)
			(stroke
				(width 0.1)
				(type default)
			)
			(layer "B.Fab")
		)
		(fp_line
			(start 0.12065 0.2794)
			(end 0.12065 0.3048)
			(stroke
				(width 0.1)
				(type default)
			)
			(layer "B.Fab")
		)
		(fp_line
			(start -0.120396 0.2794)
			(end 0.12065 0.2794)
			(stroke
				(width 0.1)
				(type default)
			)
			(layer "B.Fab")
		)
		(fp_line
			(start 0.67945 0.3048)
			(end 0.67945 -0.305054)
			(stroke
				(width 0.1)
				(type default)
			)
			(layer "B.Fab")
		)
		(fp_line
			(start 0.12065 0.3048)
			(end 0.67945 0.3048)
			(stroke
				(width 0.1)
				(type default)
			)
			(layer "B.Fab")
		)
		(fp_line
			(start -0.120396 0.3048)
			(end -0.120396 0.2794)
			(stroke
				(width 0.1)
				(type default)
			)
			(layer "B.Fab")
		)
		(fp_line
			(start -0.67945 0.3048)
			(end -0.120396 0.3048)
			(stroke
				(width 0.1)
				(type default)
			)
			(layer "B.Fab")
		)
		(pad "1" smd circle
			(at 0.40005 0 270)
			(size 0 0)
			(layers "B.Cu" "B.Mask" "B.Paste")
			(net "DBP_CPU0_HOOK9_MBP3_GTL_QS_R_N")
		)
		(pad "2" smd circle
			(at -0.40005 0 270)
			(size 0 0)
			(layers "B.Cu" "B.Mask" "B.Paste")
			(net "DBP_CPU_HOOK9_MBP3_GTL_QS_N")
		)
	)
	(footprint ""
		(layer "B.Cu")
		(at 60.873132 -258.466844 -90)
		(property "Reference" "C458"
			(at 0 0 90)
			(layer "B.SilkS")
			(hide yes)
			(effects
				(font
					(size 1.27 1.27)
				)
				(justify mirror)
			)
		)
		(property "Value" ""
			(at 0 0 90)
			(layer "B.Fab")
			(effects
				(font
					(size 1.27 1.27)
				)
				(justify mirror)
			)
		)
		(duplicate_pad_numbers_are_jumpers no)
		(fp_line
			(start -1.524 0.762)
			(end 1.524 0.762)
			(stroke
				(width 0.1524)
				(type default)
			)
			(layer "B.SilkS")
		)
		(fp_line
			(start 1.524 0.762)
			(end 1.524 -0.762)
			(stroke
				(width 0.1524)
				(type default)
			)
			(layer "B.SilkS")
		)
		(fp_line
			(start -1.524 -0.762)
			(end -1.524 0.762)
			(stroke
				(width 0.1524)
				(type default)
			)
			(layer "B.SilkS")
		)
		(fp_line
			(start 1.524 -0.762)
			(end -1.524 -0.762)
			(stroke
				(width 0.1524)
				(type default)
			)
			(layer "B.SilkS")
		)
		(fp_line
			(start -1.1049 0.724916)
			(end -1.1049 -0.724916)
			(stroke
				(width 0.1)
				(type default)
			)
			(layer "B.Fab")
		)
		(fp_line
			(start 1.1049 0.724916)
			(end -1.1049 0.724916)
			(stroke
				(width 0.1)
				(type default)
			)
			(layer "B.Fab")
		)
		(fp_line
			(start -1.1049 -0.724916)
			(end 1.1049 -0.724916)
			(stroke
				(width 0.1)
				(type default)
			)
			(layer "B.Fab")
		)
		(fp_line
			(start 1.1049 -0.724916)
			(end 1.1049 0.724916)
			(stroke
				(width 0.1)
				(type default)
			)
			(layer "B.Fab")
		)
		(pad "1" smd rect
			(at 0.889 0 270)
			(size 1.016 1.27)
			(layers "B.Cu" "B.Mask" "B.Paste")
			(net "PVCCFA_EHV_FIVRA_CPU1")
		)
		(pad "2" smd rect
			(at -0.889 0 270)
			(size 1.016 1.27)
			(layers "B.Cu" "B.Mask" "B.Paste")
			(net "GND")
		)
	)
)
